# T6G (Grand Teton) — schematic netlist excerpt (pin names and nets, part order shuffled) for the footprints in the layout excerpt that follows; sources: Cadence DE-HDL packaged netlist, KiCad conversion of 04192023_DAF0TMB3IC0_F0TG_MB_C_brd_V02_OCP.brd

C2599  Q_CAP  22UF 4V 20% X6S  pkg C0402  page 70 : A = PVDDIO_P0 ; B = GND

U143  NCT7718W  IC  pkg MSOP8_0-65_3X3XE  page 267
  VDD  = P3V3_AUX
  \d+\  = P12V_HSC_TEMP_D+
  \d-\  = P12V_HSC_TEMP_D-
  \t_crit#\  = P12V_HSC_T_CRIT_N
  GND  = GND
  \alert#\  = P12V_HSC_TEMP_ALERT_N
  SDA  = SMB_P12V_HSC_TEMP_SDA
  SCL  = SMB_P12V_HSC_TEMP_SCL

(kicad_pcb
	(version 20260206)
	(generator "pcbnew")
	(generator_version "10.0")
	(general
		(thickness 1.6)
		(legacy_teardrops no)
	)
	(paper "A4")
	(title_block
		(title "04192023_DAF0TMB3IC0_F0TG_MB_C_brd_V02_OCP.brd")
		(comment 1 "Grand Teton / footprints 4010-4011 of 8354")
	)
	(layers
		(0 "F.Cu" signal "TOP")
		(4 "In1.Cu" signal "GND")
		(6 "In2.Cu" signal "IN1")
		(8 "In3.Cu" signal "GND1")
		(10 "In4.Cu" signal "IN2")
		(12 "In5.Cu" signal "GND2")
		(14 "In6.Cu" signal "IN3")
		(16 "In7.Cu" signal "GND3")
		(18 "In8.Cu" signal "VCC")
		(20 "In9.Cu" signal "VCC1")
		(22 "In10.Cu" signal "GND4")
		(24 "In11.Cu" signal "IN4")
		(26 "In12.Cu" signal "GND5")
		(28 "In13.Cu" signal "IN5")
		(30 "In14.Cu" signal "GND6")
		(32 "In15.Cu" signal "IN6")
		(34 "In16.Cu" signal "GND7")
		(2 "B.Cu" signal "BOTTOM")
		(9 "F.Adhes" user "F.Adhesive")
		(11 "B.Adhes" user "B.Adhesive")
		(13 "F.Paste" user "Package Geometry/Pastemask Top")
		(15 "B.Paste" user "Package Geometry/Pastemask Bottom")
		(5 "F.SilkS" user "Ref Des/Silkscreen Top")
		(7 "B.SilkS" user "Ref Des/Silkscreen Bottom")
		(1 "F.Mask" user "Board Geometry/Soldermask Top")
		(3 "B.Mask" user "Board Geometry/Soldermask Bottom")
		(17 "Dwgs.User" user "User.Drawings")
		(19 "Cmts.User" user "User.Comments")
		(21 "Eco1.User" user "User.Eco1")
		(23 "Eco2.User" user "User.Eco2")
		(25 "Edge.Cuts" user "Board Geometry/Outline")
		(27 "Margin" user)
		(31 "F.CrtYd" user "Package Geometry/Place Bound Top")
		(29 "B.CrtYd" user "Package Geometry/Place Bound Bottom")
		(35 "F.Fab" user "Ref Des/Assembly Top")
		(33 "B.Fab" user "Ref Des/Assembly Bottom")
	)
	(footprint ""
		(layer "F.Cu")
		(at 353.900232 -258.405122)
		(property "Reference" "C2599"
			(at 0 0 0)
			(layer "F.SilkS")
			(hide yes)
			(effects
				(font
					(size 1.27 1.27)
				)
			)
		)
		(property "Value" ""
			(at 0 0 0)
			(layer "F.Fab")
			(effects
				(font
					(size 1.27 1.27)
				)
			)
		)
		(duplicate_pad_numbers_are_jumpers no)
		(fp_line
			(start -0.7874 -0.4064)
			(end 0.7874 -0.4064)
			(stroke
				(width 0.1524)
				(type default)
			)
			(layer "F.SilkS")
		)
		(fp_line
			(start -0.7874 0.4064)
			(end -0.7874 -0.4064)
			(stroke
				(width 0.1524)
				(type default)
			)
			(layer "F.SilkS")
		)
		(fp_line
			(start 0.7874 -0.4064)
			(end 0.7874 0.4064)
			(stroke
				(width 0.1524)
				(type default)
			)
			(layer "F.SilkS")
		)
		(fp_line
			(start 0.7874 0.4064)
			(end -0.7874 0.4064)
			(stroke
				(width 0.1524)
				(type default)
			)
			(layer "F.SilkS")
		)
		(fp_line
			(start -0.67945 -0.305054)
			(end -0.12065 -0.305054)
			(stroke
				(width 0.1)
				(type default)
			)
			(layer "F.Fab")
		)
		(fp_line
			(start -0.67945 0.3048)
			(end -0.67945 -0.305054)
			(stroke
				(width 0.1)
				(type default)
			)
			(layer "F.Fab")
		)
		(fp_line
			(start -0.12065 -0.305054)
			(end -0.12065 -0.2794)
			(stroke
				(width 0.1)
				(type default)
			)
			(layer "F.Fab")
		)
		(fp_line
			(start -0.12065 -0.2794)
			(end 0.12065 -0.2794)
			(stroke
				(width 0.1)
				(type default)
			)
			(layer "F.Fab")
		)
		(fp_line
			(start -0.12065 0.2794)
			(end -0.12065 0.3048)
			(stroke
				(width 0.1)
				(type default)
			)
			(layer "F.Fab")
		)
		(fp_line
			(start -0.12065 0.3048)
			(end -0.67945 0.3048)
			(stroke
				(width 0.1)
				(type default)
			)
			(layer "F.Fab")
		)
		(fp_line
			(start 0.120396 0.2794)
			(end -0.12065 0.2794)
			(stroke
				(width 0.1)
				(type default)
			)
			(layer "F.Fab")
		)
		(fp_line
			(start 0.120396 0.3048)
			(end 0.120396 0.2794)
			(stroke
				(width 0.1)
				(type default)
			)
			(layer "F.Fab")
		)
		(fp_line
			(start 0.12065 -0.3048)
			(end 0.67945 -0.3048)
			(stroke
				(width 0.1)
				(type default)
			)
			(layer "F.Fab")
		)
		(fp_line
			(start 0.12065 -0.2794)
			(end 0.12065 -0.3048)
			(stroke
				(width 0.1)
				(type default)
			)
			(layer "F.Fab")
		)
		(fp_line
			(start 0.67945 -0.3048)
			(end 0.67945 0.3048)
			(stroke
				(width 0.1)
				(type default)
			)
			(layer "F.Fab")
		)
		(fp_line
			(start 0.67945 0.3048)
			(end 0.120396 0.3048)
			(stroke
				(width 0.1)
				(type default)
			)
			(layer "F.Fab")
		)
		(pad "1" smd circle
			(at -0.40005 0)
			(size 0 0)
			(layers "F.Cu" "F.Mask" "F.Paste")
			(net "PVDDIO_P0")
		)
		(pad "2" smd circle
			(at 0.40005 0)
			(size 0 0)
			(layers "F.Cu" "F.Mask" "F.Paste")
			(net "GND")
		)
	)
	(footprint ""
		(layer "F.Cu")
		(at 285.218124 -395.22019 -90)
		(property "Reference" "U143"
			(at 2.42951 -2.26187 90)
			(unlocked yes)
			(layer "F.SilkS")
			(effects
				(font
					(size 0.7874 0.5842)
					(thickness 0.1524)
				)
				(justify left)
			)
		)
		(property "Value" ""
			(at 0 0 270)
			(layer "F.Fab")
			(effects
				(font
					(size 1.27 1.27)
				)
			)
		)
		(duplicate_pad_numbers_are_jumpers no)
		(fp_line
			(start -1.448308 1.549908)
			(end -1.448308 -1.549908)
			(stroke
				(width 0.1524)
				(type default)
			)
			(layer "F.SilkS")
		)
		(fp_line
			(start 1.448308 1.549908)
			(end -1.448308 1.549908)
			(stroke
				(width 0.1524)
				(type default)
			)
			(layer "F.SilkS")
		)
		(fp_line
			(start 0 -0.533908)
			(end 0.774954 -1.549908)
			(stroke
				(width 0.1524)
				(type default)
			)
			(layer "F.SilkS")
		)
		(fp_line
			(start -1.448308 -1.549908)
			(end -0.774954 -1.549908)
			(stroke
				(width 0.1524)
				(type default)
			)
			(layer "F.SilkS")
		)
		(fp_line
			(start -0.774954 -1.549908)
			(end 0 -0.533908)
			(stroke
				(width 0.1524)
				(type default)
			)
			(layer "F.SilkS")
		)
		(fp_line
			(start 0.774954 -1.549908)
			(end 1.448308 -1.549908)
			(stroke
				(width 0.1524)
				(type default)
			)
			(layer "F.SilkS")
		)
		(fp_line
			(start 1.448308 -1.549908)
			(end 1.448308 1.549908)
			(stroke
				(width 0.1524)
				(type default)
			)
			(layer "F.SilkS")
		)
		(fp_rect
			(start -1.549908 -1.549908)
			(end -0.787908 -1.880108)
			(stroke
				(width 0)
				(type default)
			)
			(fill yes)
			(layer "F.SilkS")
		)
		(fp_line
			(start -1.549908 1.549908)
			(end -1.549908 -1.549908)
			(stroke
				(width 0.1)
				(type default)
			)
			(layer "F.Fab")
		)
		(fp_line
			(start 1.549908 1.549908)
			(end -1.549908 1.549908)
			(stroke
				(width 0.1)
				(type default)
			)
			(layer "F.Fab")
		)
		(fp_line
			(start -1.549908 -1.549908)
			(end 1.549908 -1.549908)
			(stroke
				(width 0.1)
				(type default)
			)
			(layer "F.Fab")
		)
		(fp_line
			(start 1.549908 -1.549908)
			(end 1.549908 1.549908)
			(stroke
				(width 0.1)
				(type default)
			)
			(layer "F.Fab")
		)
		(fp_poly
			(pts
				(xy -1.549908 -1.549908) (xy -0.787908 -1.549908) (xy -0.787908 -1.880108) (xy -1.549908 -1.880108)
			)
			(stroke
				(width 0)
				(type default)
			)
			(fill yes)
			(layer "F.Fab")
		)
		(pad "1" smd rect
			(at -2.350008 -0.975106 180)
			(size 0.4318 1.4986)
			(layers "F.Cu" "F.Mask" "F.Paste")
			(net "P3V3_AUX")
		)
		(pad "2" smd rect
			(at -2.350008 -0.32512 180)
			(size 0.4318 1.4986)
			(layers "F.Cu" "F.Mask" "F.Paste")
			(net "P12V_HSC_TEMP_D+")
		)
		(pad "3" smd rect
			(at -2.350008 0.32512 180)
			(size 0.4318 1.4986)
			(layers "F.Cu" "F.Mask" "F.Paste")
			(net "P12V_HSC_TEMP_D-")
		)
		(pad "4" smd rect
			(at -2.350008 0.975106 180)
			(size 0.4318 1.4986)
			(layers "F.Cu" "F.Mask" "F.Paste")
			(net "P12V_HSC_T_CRIT_N")
		)
		(pad "5" smd rect
			(at 2.350008 0.975106 180)
			(size 0.4318 1.4986)
			(layers "F.Cu" "F.Mask" "F.Paste")
			(net "GND")
		)
		(pad "6" smd rect
			(at 2.350008 0.32512 180)
			(size 0.4318 1.4986)
			(layers "F.Cu" "F.Mask" "F.Paste")
			(net "P12V_HSC_TEMP_ALERT_N")
		)
		(pad "7" smd rect
			(at 2.350008 -0.32512 180)
			(size 0.4318 1.4986)
			(layers "F.Cu" "F.Mask" "F.Paste")
			(net "SMB_P12V_HSC_TEMP_SDA")
		)
		(pad "8" smd rect
			(at 2.350008 -0.975106 180)
			(size 0.4318 1.4986)
			(layers "F.Cu" "F.Mask" "F.Paste")
			(net "SMB_P12V_HSC_TEMP_SCL")
		)
	)
)
